# T6G (Grand Teton) — schematic netlist excerpt (pin names and nets, part order shuffled) for the footprints in the layout excerpt that follows; sources: Cadence DE-HDL packaged netlist, KiCad conversion of 04192023_DAF0TMB3IC0_F0TG_MB_C_brd_V02_OCP.brd

D81  Q_LED  IC  pkg SMLF  page 256 : A = LED_PWRGD_PVDDCR_SOC_P1_R ; C = LED_PWRGD_PVDDCR_SOC_P1_D
C8003  Q_CAP  0.1UF 25V 10% EMPTY  pkg 0402  page 143 : A = OCP_V3_2_PRSNT01_R1_N ; B = GND

(kicad_pcb
	(version 20260206)
	(generator "pcbnew")
	(generator_version "10.0")
	(general
		(thickness 1.6)
		(legacy_teardrops no)
	)
	(paper "A4")
	(title_block
		(title "04192023_DAF0TMB3IC0_F0TG_MB_C_brd_V02_OCP.brd")
		(comment 1 "Grand Teton / footprints 4030-4031 of 8354")
	)
	(layers
		(0 "F.Cu" signal "TOP")
		(4 "In1.Cu" signal "GND")
		(6 "In2.Cu" signal "IN1")
		(8 "In3.Cu" signal "GND1")
		(10 "In4.Cu" signal "IN2")
		(12 "In5.Cu" signal "GND2")
		(14 "In6.Cu" signal "IN3")
		(16 "In7.Cu" signal "GND3")
		(18 "In8.Cu" signal "VCC")
		(20 "In9.Cu" signal "VCC1")
		(22 "In10.Cu" signal "GND4")
		(24 "In11.Cu" signal "IN4")
		(26 "In12.Cu" signal "GND5")
		(28 "In13.Cu" signal "IN5")
		(30 "In14.Cu" signal "GND6")
		(32 "In15.Cu" signal "IN6")
		(34 "In16.Cu" signal "GND7")
		(2 "B.Cu" signal "BOTTOM")
		(9 "F.Adhes" user "F.Adhesive")
		(11 "B.Adhes" user "B.Adhesive")
		(13 "F.Paste" user "Package Geometry/Pastemask Top")
		(15 "B.Paste" user "Package Geometry/Pastemask Bottom")
		(5 "F.SilkS" user "Ref Des/Silkscreen Top")
		(7 "B.SilkS" user "Ref Des/Silkscreen Bottom")
		(1 "F.Mask" user "Board Geometry/Soldermask Top")
		(3 "B.Mask" user "Board Geometry/Soldermask Bottom")
		(17 "Dwgs.User" user "User.Drawings")
		(19 "Cmts.User" user "User.Comments")
		(21 "Eco1.User" user "User.Eco1")
		(23 "Eco2.User" user "User.Eco2")
		(25 "Edge.Cuts" user "Board Geometry/Outline")
		(27 "Margin" user)
		(31 "F.CrtYd" user "Package Geometry/Place Bound Top")
		(29 "B.CrtYd" user "Package Geometry/Place Bound Bottom")
		(35 "F.Fab" user "Ref Des/Assembly Top")
		(33 "B.Fab" user "Ref Des/Assembly Bottom")
	)
	(footprint ""
		(layer "F.Cu")
		(at 16.764 -73.66)
		(property "Reference" "C8003"
			(at 0 0 0)
			(layer "F.SilkS")
			(hide yes)
			(effects
				(font
					(size 1.27 1.27)
				)
			)
		)
		(property "Value" ""
			(at 0 0 0)
			(layer "F.Fab")
			(effects
				(font
					(size 1.27 1.27)
				)
			)
		)
		(duplicate_pad_numbers_are_jumpers no)
		(fp_line
			(start -0.7874 -0.4064)
			(end 0.7874 -0.4064)
			(stroke
				(width 0.1524)
				(type default)
			)
			(layer "F.SilkS")
		)
		(fp_line
			(start -0.7874 0.4064)
			(end -0.7874 -0.4064)
			(stroke
				(width 0.1524)
				(type default)
			)
			(layer "F.SilkS")
		)
		(fp_line
			(start 0.7874 -0.4064)
			(end 0.7874 0.4064)
			(stroke
				(width 0.1524)
				(type default)
			)
			(layer "F.SilkS")
		)
		(fp_line
			(start 0.7874 0.4064)
			(end -0.7874 0.4064)
			(stroke
				(width 0.1524)
				(type default)
			)
			(layer "F.SilkS")
		)
		(fp_line
			(start -0.67945 -0.305054)
			(end -0.12065 -0.305054)
			(stroke
				(width 0.1)
				(type default)
			)
			(layer "F.Fab")
		)
		(fp_line
			(start -0.67945 0.3048)
			(end -0.67945 -0.305054)
			(stroke
				(width 0.1)
				(type default)
			)
			(layer "F.Fab")
		)
		(fp_line
			(start -0.12065 -0.305054)
			(end -0.12065 -0.2794)
			(stroke
				(width 0.1)
				(type default)
			)
			(layer "F.Fab")
		)
		(fp_line
			(start -0.12065 -0.2794)
			(end 0.12065 -0.2794)
			(stroke
				(width 0.1)
				(type default)
			)
			(layer "F.Fab")
		)
		(fp_line
			(start -0.12065 0.2794)
			(end -0.12065 0.3048)
			(stroke
				(width 0.1)
				(type default)
			)
			(layer "F.Fab")
		)
		(fp_line
			(start -0.12065 0.3048)
			(end -0.67945 0.3048)
			(stroke
				(width 0.1)
				(type default)
			)
			(layer "F.Fab")
		)
		(fp_line
			(start 0.120396 0.2794)
			(end -0.12065 0.2794)
			(stroke
				(width 0.1)
				(type default)
			)
			(layer "F.Fab")
		)
		(fp_line
			(start 0.120396 0.3048)
			(end 0.120396 0.2794)
			(stroke
				(width 0.1)
				(type default)
			)
			(layer "F.Fab")
		)
		(fp_line
			(start 0.12065 -0.3048)
			(end 0.67945 -0.3048)
			(stroke
				(width 0.1)
				(type default)
			)
			(layer "F.Fab")
		)
		(fp_line
			(start 0.12065 -0.2794)
			(end 0.12065 -0.3048)
			(stroke
				(width 0.1)
				(type default)
			)
			(layer "F.Fab")
		)
		(fp_line
			(start 0.67945 -0.3048)
			(end 0.67945 0.3048)
			(stroke
				(width 0.1)
				(type default)
			)
			(layer "F.Fab")
		)
		(fp_line
			(start 0.67945 0.3048)
			(end 0.120396 0.3048)
			(stroke
				(width 0.1)
				(type default)
			)
			(layer "F.Fab")
		)
		(pad "1" smd circle
			(at -0.40005 0)
			(size 0 0)
			(layers "F.Cu" "F.Mask" "F.Paste")
			(net "OCP_V3_2_PRSNT01_R1_N")
		)
		(pad "2" smd circle
			(at 0.40005 0)
			(size 0 0)
			(layers "F.Cu" "F.Mask" "F.Paste")
			(net "GND")
		)
	)
	(footprint ""
		(layer "F.Cu")
		(at 338.859876 -70.098412 90)
		(property "Reference" "D81"
			(at -3.934714 -0.691642 90)
			(unlocked yes)
			(layer "F.SilkS")
			(effects
				(font
					(size 0.7874 0.5842)
					(thickness 0.1524)
				)
				(justify left)
			)
		)
		(property "Value" ""
			(at 0 0 90)
			(layer "F.Fab")
			(effects
				(font
					(size 1.27 1.27)
				)
			)
		)
		(duplicate_pad_numbers_are_jumpers no)
		(fp_line
			(start 1.16078 -0.4826)
			(end 1.16078 0.4826)
			(stroke
				(width 0.1524)
				(type default)
			)
			(layer "F.SilkS")
		)
		(fp_line
			(start 1.03378 -0.4826)
			(end 1.03378 0.4826)
			(stroke
				(width 0.1524)
				(type default)
			)
			(layer "F.SilkS")
		)
		(fp_line
			(start 0.90678 -0.4826)
			(end 0.90678 0.4826)
			(stroke
				(width 0.1524)
				(type default)
			)
			(layer "F.SilkS")
		)
		(fp_line
			(start -0.64008 -0.4826)
			(end 1.16078 -0.4826)
			(stroke
				(width 0.1524)
				(type default)
			)
			(layer "F.SilkS")
		)
		(fp_line
			(start -0.79248 -0.4826)
			(end 1.03378 -0.4826)
			(stroke
				(width 0.1524)
				(type default)
			)
			(layer "F.SilkS")
		)
		(fp_line
			(start -0.89408 -0.4826)
			(end 0.90678 -0.4826)
			(stroke
				(width 0.1524)
				(type default)
			)
			(layer "F.SilkS")
		)
		(fp_line
			(start 1.16078 0.4826)
			(end -0.64008 0.4826)
			(stroke
				(width 0.1524)
				(type default)
			)
			(layer "F.SilkS")
		)
		(fp_line
			(start 1.03378 0.4826)
			(end -0.79248 0.4826)
			(stroke
				(width 0.1524)
				(type default)
			)
			(layer "F.SilkS")
		)
		(fp_line
			(start 0.90678 0.4826)
			(end -0.90678 0.4826)
			(stroke
				(width 0.1524)
				(type default)
			)
			(layer "F.SilkS")
		)
		(fp_line
			(start -0.90678 0.4826)
			(end -0.90678 -0.4699)
			(stroke
				(width 0.1524)
				(type default)
			)
			(layer "F.SilkS")
		)
		(fp_line
			(start 0.499872 -0.249936)
			(end 0.499872 0.249936)
			(stroke
				(width 0.1)
				(type default)
			)
			(layer "F.Fab")
		)
		(fp_line
			(start -0.499872 -0.249936)
			(end 0.499872 -0.249936)
			(stroke
				(width 0.1)
				(type default)
			)
			(layer "F.Fab")
		)
		(fp_line
			(start 0.499872 0.249936)
			(end -0.499872 0.249936)
			(stroke
				(width 0.1)
				(type default)
			)
			(layer "F.Fab")
		)
		(fp_line
			(start -0.499872 0.249936)
			(end -0.499872 -0.249936)
			(stroke
				(width 0.1)
				(type default)
			)
			(layer "F.Fab")
		)
		(pad "A" smd rect
			(at -0.47498 0 90)
			(size 0.6096 0.7112)
			(layers "F.Cu" "F.Mask" "F.Paste")
			(net "LED_PWRGD_PVDDCR_SOC_P1_R")
		)
		(pad "C" smd rect
			(at 0.47498 0 90)
			(size 0.6096 0.7112)
			(layers "F.Cu" "F.Mask" "F.Paste")
			(net "LED_PWRGD_PVDDCR_SOC_P1_D")
		)
	)
)
